(kicad_pcb
	(version 20260206)
	(generator "pcbnew")
	(generator_version "10.0")
	(general
		(thickness 1.6)
		(legacy_teardrops no)
	)
	(paper "A4")
	(title_block
		(title "12092022_DA0F0TMDCD0_F0T_Management_Board_D_brd_V3_OCP.brd")
		(comment 1 "Grand Teton / footprints 1291-1296 of 1440")
	)
	(layers
		(0 "F.Cu" signal "TOP")
		(4 "In1.Cu" signal "GND")
		(6 "In2.Cu" signal "IN1")
		(8 "In3.Cu" signal "GND1")
		(10 "In4.Cu" signal "IN2")
		(12 "In5.Cu" signal "VCC")
		(14 "In6.Cu" signal "VCC1")
		(16 "In7.Cu" signal "IN3")
		(18 "In8.Cu" signal "GND2")
		(20 "In9.Cu" signal "IN4")
		(22 "In10.Cu" signal "GND3")
		(2 "B.Cu" signal "BOTTOM")
		(9 "F.Adhes" user "F.Adhesive")
		(11 "B.Adhes" user "B.Adhesive")
		(13 "F.Paste" user "Package Geometry/Pastemask Top")
		(15 "B.Paste" user "Package Geometry/Pastemask Bottom")
		(5 "F.SilkS" user "Ref Des/Silkscreen Top")
		(7 "B.SilkS" user "Ref Des/Silkscreen Bottom")
		(1 "F.Mask" user "Board Geometry/Soldermask Top")
		(3 "B.Mask" user "Board Geometry/Soldermask Bottom")
		(17 "Dwgs.User" user "User.Drawings")
		(19 "Cmts.User" user "User.Comments")
		(21 "Eco1.User" user "User.Eco1")
		(23 "Eco2.User" user "User.Eco2")
		(25 "Edge.Cuts" user "Board Geometry/Outline")
		(27 "Margin" user)
		(31 "F.CrtYd" user "Package Geometry/Place Bound Top")
		(29 "B.CrtYd" user "Package Geometry/Place Bound Bottom")
		(35 "F.Fab" user "Ref Des/Assembly Top")
		(33 "B.Fab" user "Ref Des/Assembly Bottom")
	)
	(footprint ""
		(layer "B.Cu")
		(at 51.3715 -86.0425 180)
		(property "Reference" "R701"
			(at 0 0 0)
			(layer "B.SilkS")
			(hide yes)
			(effects
				(font
					(size 1.27 1.27)
				)
				(justify mirror)
			)
		)
		(property "Value" ""
			(at 0 0 0)
			(layer "B.Fab")
			(effects
				(font
					(size 1.27 1.27)
				)
				(justify mirror)
			)
		)
		(duplicate_pad_numbers_are_jumpers no)
		(fp_line
			(start 0.7874 0.4064)
			(end 0.7874 -0.4064)
			(stroke
				(width 0.1524)
				(type default)
			)
			(layer "B.SilkS")
		)
		(fp_line
			(start 0.7874 -0.4064)
			(end -0.7874 -0.4064)
			(stroke
				(width 0.1524)
				(type default)
			)
			(layer "B.SilkS")
		)
		(fp_line
			(start -0.7874 0.4064)
			(end 0.7874 0.4064)
			(stroke
				(width 0.1524)
				(type default)
			)
			(layer "B.SilkS")
		)
		(fp_line
			(start -0.7874 -0.4064)
			(end -0.7874 0.4064)
			(stroke
				(width 0.1524)
				(type default)
			)
			(layer "B.SilkS")
		)
		(fp_line
			(start 0.67945 0.3048)
			(end 0.67945 -0.305054)
			(stroke
				(width 0.1)
				(type default)
			)
			(layer "B.Fab")
		)
		(fp_line
			(start 0.67945 -0.305054)
			(end 0.12065 -0.305054)
			(stroke
				(width 0.1)
				(type default)
			)
			(layer "B.Fab")
		)
		(fp_line
			(start 0.12065 0.3048)
			(end 0.67945 0.3048)
			(stroke
				(width 0.1)
				(type default)
			)
			(layer "B.Fab")
		)
		(fp_line
			(start 0.12065 0.2794)
			(end 0.12065 0.3048)
			(stroke
				(width 0.1)
				(type default)
			)
			(layer "B.Fab")
		)
		(fp_line
			(start 0.12065 -0.2794)
			(end -0.12065 -0.2794)
			(stroke
				(width 0.1)
				(type default)
			)
			(layer "B.Fab")
		)
		(fp_line
			(start 0.12065 -0.305054)
			(end 0.12065 -0.2794)
			(stroke
				(width 0.1)
				(type default)
			)
			(layer "B.Fab")
		)
		(fp_line
			(start -0.120396 0.3048)
			(end -0.120396 0.2794)
			(stroke
				(width 0.1)
				(type default)
			)
			(layer "B.Fab")
		)
		(fp_line
			(start -0.120396 0.2794)
			(end 0.12065 0.2794)
			(stroke
				(width 0.1)
				(type default)
			)
			(layer "B.Fab")
		)
		(fp_line
			(start -0.12065 -0.2794)
			(end -0.12065 -0.3048)
			(stroke
				(width 0.1)
				(type default)
			)
			(layer "B.Fab")
		)
		(fp_line
			(start -0.12065 -0.3048)
			(end -0.67945 -0.3048)
			(stroke
				(width 0.1)
				(type default)
			)
			(layer "B.Fab")
		)
		(fp_line
			(start -0.67945 0.3048)
			(end -0.120396 0.3048)
			(stroke
				(width 0.1)
				(type default)
			)
			(layer "B.Fab")
		)
		(fp_line
			(start -0.67945 -0.3048)
			(end -0.67945 0.3048)
			(stroke
				(width 0.1)
				(type default)
			)
			(layer "B.Fab")
		)
		(pad "1" smd circle
			(at 0.40005 0)
			(size 0 0)
			(layers "B.Cu" "B.Mask" "B.Paste")
			(net "PWRGD_SYS_PWROK")
		)
		(pad "2" smd circle
			(at -0.40005 0)
			(size 0 0)
			(layers "B.Cu" "B.Mask" "B.Paste")
			(net "PWRGD_SYS_PWROK_R1")
		)
	)
	(footprint ""
		(layer "B.Cu")
		(at 17.864328 -96.782128 -90)
		(property "Reference" "C254"
			(at 0 0 90)
			(layer "B.SilkS")
			(hide yes)
			(effects
				(font
					(size 1.27 1.27)
				)
				(justify mirror)
			)
		)
		(property "Value" ""
			(at 0 0 90)
			(layer "B.Fab")
			(effects
				(font
					(size 1.27 1.27)
				)
				(justify mirror)
			)
		)
		(duplicate_pad_numbers_are_jumpers no)
		(fp_line
			(start -0.69215 0.2921)
			(end 0.69215 0.2921)
			(stroke
				(width 0.1524)
				(type default)
			)
			(layer "B.SilkS")
		)
		(fp_line
			(start 0.69215 0.2921)
			(end 0.69215 -0.2921)
			(stroke
				(width 0.1524)
				(type default)
			)
			(layer "B.SilkS")
		)
		(fp_line
			(start -0.69215 -0.2921)
			(end -0.69215 0.2921)
			(stroke
				(width 0.1524)
				(type default)
			)
			(layer "B.SilkS")
		)
		(fp_line
			(start 0.69215 -0.2921)
			(end -0.69215 -0.2921)
			(stroke
				(width 0.1524)
				(type default)
			)
			(layer "B.SilkS")
		)
		(fp_line
			(start -0.51435 0.2794)
			(end 0.51435 0.2794)
			(stroke
				(width 0.1)
				(type default)
			)
			(layer "B.Fab")
		)
		(fp_line
			(start 0.51435 0.2794)
			(end 0.51435 -0.2794)
			(stroke
				(width 0.1)
				(type default)
			)
			(layer "B.Fab")
		)
		(fp_line
			(start -0.51435 -0.2794)
			(end -0.51435 0.2794)
			(stroke
				(width 0.1)
				(type default)
			)
			(layer "B.Fab")
		)
		(fp_line
			(start 0.51435 -0.2794)
			(end -0.51435 -0.2794)
			(stroke
				(width 0.1)
				(type default)
			)
			(layer "B.Fab")
		)
		(pad "1" smd circle
			(at 0.40005 0 90)
			(size 0 0)
			(layers "B.Cu" "B.Mask" "B.Paste")
			(net "VCCIO1")
		)
		(pad "2" smd circle
			(at -0.40005 0 90)
			(size 0 0)
			(layers "B.Cu" "B.Mask" "B.Paste")
			(net "GND")
		)
		(zone
			(layer "B.Cu")
			(hatch none 0.5)
			(connect_pads
				(clearance 0)
			)
			(min_thickness 0.25)
			(keepout
				(tracks not_allowed)
				(vias allowed)
				(pads allowed)
				(copperpour not_allowed)
				(footprints allowed)
			)
			(placement
				(enabled no)
				(sheetname "")
			)
			(fill
				(thermal_gap 0.5)
				(thermal_bridge_width 0.5)
				(island_removal_mode 0)
			)
			(polygon
				(pts
					(xy 17.776698 -96.591628) (xy 17.718532 -96.683068) (xy 17.718532 -96.882458) (xy 17.776698 -96.972628)
					(xy 17.951958 -96.972628) (xy 18.010378 -96.882458) (xy 18.010378 -96.683068) (xy 17.952212 -96.591628)
				)
			)
		)
	)
	(footprint ""
		(layer "B.Cu")
		(at 39.8526 -30.2768 180)
		(property "Reference" "R761"
			(at 0 0 0)
			(layer "B.SilkS")
			(hide yes)
			(effects
				(font
					(size 1.27 1.27)
				)
				(justify mirror)
			)
		)
		(property "Value" ""
			(at 0 0 0)
			(layer "B.Fab")
			(effects
				(font
					(size 1.27 1.27)
				)
				(justify mirror)
			)
		)
		(duplicate_pad_numbers_are_jumpers no)
		(fp_line
			(start 0.7874 0.4064)
			(end 0.7874 -0.4064)
			(stroke
				(width 0.1524)
				(type default)
			)
			(layer "B.SilkS")
		)
		(fp_line
			(start 0.7874 -0.4064)
			(end -0.7874 -0.4064)
			(stroke
				(width 0.1524)
				(type default)
			)
			(layer "B.SilkS")
		)
		(fp_line
			(start -0.7874 0.4064)
			(end 0.7874 0.4064)
			(stroke
				(width 0.1524)
				(type default)
			)
			(layer "B.SilkS")
		)
		(fp_line
			(start -0.7874 -0.4064)
			(end -0.7874 0.4064)
			(stroke
				(width 0.1524)
				(type default)
			)
			(layer "B.SilkS")
		)
		(fp_line
			(start 0.67945 0.3048)
			(end 0.67945 -0.305054)
			(stroke
				(width 0.1)
				(type default)
			)
			(layer "B.Fab")
		)
		(fp_line
			(start 0.67945 -0.305054)
			(end 0.12065 -0.305054)
			(stroke
				(width 0.1)
				(type default)
			)
			(layer "B.Fab")
		)
		(fp_line
			(start 0.12065 0.3048)
			(end 0.67945 0.3048)
			(stroke
				(width 0.1)
				(type default)
			)
			(layer "B.Fab")
		)
		(fp_line
			(start 0.12065 0.2794)
			(end 0.12065 0.3048)
			(stroke
				(width 0.1)
				(type default)
			)
			(layer "B.Fab")
		)
		(fp_line
			(start 0.12065 -0.2794)
			(end -0.12065 -0.2794)
			(stroke
				(width 0.1)
				(type default)
			)
			(layer "B.Fab")
		)
		(fp_line
			(start 0.12065 -0.305054)
			(end 0.12065 -0.2794)
			(stroke
				(width 0.1)
				(type default)
			)
			(layer "B.Fab")
		)
		(fp_line
			(start -0.120396 0.3048)
			(end -0.120396 0.2794)
			(stroke
				(width 0.1)
				(type default)
			)
			(layer "B.Fab")
		)
		(fp_line
			(start -0.120396 0.2794)
			(end 0.12065 0.2794)
			(stroke
				(width 0.1)
				(type default)
			)
			(layer "B.Fab")
		)
		(fp_line
			(start -0.12065 -0.2794)
			(end -0.12065 -0.3048)
			(stroke
				(width 0.1)
				(type default)
			)
			(layer "B.Fab")
		)
		(fp_line
			(start -0.12065 -0.3048)
			(end -0.67945 -0.3048)
			(stroke
				(width 0.1)
				(type default)
			)
			(layer "B.Fab")
		)
		(fp_line
			(start -0.67945 0.3048)
			(end -0.120396 0.3048)
			(stroke
				(width 0.1)
				(type default)
			)
			(layer "B.Fab")
		)
		(fp_line
			(start -0.67945 -0.3048)
			(end -0.67945 0.3048)
			(stroke
				(width 0.1)
				(type default)
			)
			(layer "B.Fab")
		)
		(pad "1" smd circle
			(at 0.40005 0)
			(size 0 0)
			(layers "B.Cu" "B.Mask" "B.Paste")
			(net "UART_6_BMC_TXD")
		)
		(pad "2" smd circle
			(at -0.40005 0)
			(size 0 0)
			(layers "B.Cu" "B.Mask" "B.Paste")
			(net "UART_6_BMC_R_TXD")
		)
	)
	(footprint ""
		(layer "B.Cu")
		(at 46.9646 -70.9168 180)
		(property "Reference" "R679"
			(at 0 0 0)
			(layer "B.SilkS")
			(hide yes)
			(effects
				(font
					(size 1.27 1.27)
				)
				(justify mirror)
			)
		)
		(property "Value" ""
			(at 0 0 0)
			(layer "B.Fab")
			(effects
				(font
					(size 1.27 1.27)
				)
				(justify mirror)
			)
		)
		(duplicate_pad_numbers_are_jumpers no)
		(fp_line
			(start 0.7874 0.4064)
			(end 0.7874 -0.4064)
			(stroke
				(width 0.1524)
				(type default)
			)
			(layer "B.SilkS")
		)
		(fp_line
			(start 0.7874 -0.4064)
			(end -0.7874 -0.4064)
			(stroke
				(width 0.1524)
				(type default)
			)
			(layer "B.SilkS")
		)
		(fp_line
			(start -0.7874 0.4064)
			(end 0.7874 0.4064)
			(stroke
				(width 0.1524)
				(type default)
			)
			(layer "B.SilkS")
		)
		(fp_line
			(start -0.7874 -0.4064)
			(end -0.7874 0.4064)
			(stroke
				(width 0.1524)
				(type default)
			)
			(layer "B.SilkS")
		)
		(fp_line
			(start 0.67945 0.3048)
			(end 0.67945 -0.305054)
			(stroke
				(width 0.1)
				(type default)
			)
			(layer "B.Fab")
		)
		(fp_line
			(start 0.67945 -0.305054)
			(end 0.12065 -0.305054)
			(stroke
				(width 0.1)
				(type default)
			)
			(layer "B.Fab")
		)
		(fp_line
			(start 0.12065 0.3048)
			(end 0.67945 0.3048)
			(stroke
				(width 0.1)
				(type default)
			)
			(layer "B.Fab")
		)
		(fp_line
			(start 0.12065 0.2794)
			(end 0.12065 0.3048)
			(stroke
				(width 0.1)
				(type default)
			)
			(layer "B.Fab")
		)
		(fp_line
			(start 0.12065 -0.2794)
			(end -0.12065 -0.2794)
			(stroke
				(width 0.1)
				(type default)
			)
			(layer "B.Fab")
		)
		(fp_line
			(start 0.12065 -0.305054)
			(end 0.12065 -0.2794)
			(stroke
				(width 0.1)
				(type default)
			)
			(layer "B.Fab")
		)
		(fp_line
			(start -0.120396 0.3048)
			(end -0.120396 0.2794)
			(stroke
				(width 0.1)
				(type default)
			)
			(layer "B.Fab")
		)
		(fp_line
			(start -0.120396 0.2794)
			(end 0.12065 0.2794)
			(stroke
				(width 0.1)
				(type default)
			)
			(layer "B.Fab")
		)
		(fp_line
			(start -0.12065 -0.2794)
			(end -0.12065 -0.3048)
			(stroke
				(width 0.1)
				(type default)
			)
			(layer "B.Fab")
		)
		(fp_line
			(start -0.12065 -0.3048)
			(end -0.67945 -0.3048)
			(stroke
				(width 0.1)
				(type default)
			)
			(layer "B.Fab")
		)
		(fp_line
			(start -0.67945 0.3048)
			(end -0.120396 0.3048)
			(stroke
				(width 0.1)
				(type default)
			)
			(layer "B.Fab")
		)
		(fp_line
			(start -0.67945 -0.3048)
			(end -0.67945 0.3048)
			(stroke
				(width 0.1)
				(type default)
			)
			(layer "B.Fab")
		)
		(pad "1" smd circle
			(at 0.40005 0)
			(size 0 0)
			(layers "B.Cu" "B.Mask" "B.Paste")
			(net "SPI_BMC_MOSI_IO0_R")
		)
		(pad "2" smd circle
			(at -0.40005 0)
			(size 0 0)
			(layers "B.Cu" "B.Mask" "B.Paste")
			(net "QSPI_2_PLD_IO0")
		)
	)
	(footprint ""
		(layer "B.Cu")
		(at 4.2672 -28.1686 -90)
		(property "Reference" "R102"
			(at 0 0 90)
			(layer "B.SilkS")
			(hide yes)
			(effects
				(font
					(size 1.27 1.27)
				)
				(justify mirror)
			)
		)
		(property "Value" ""
			(at 0 0 90)
			(layer "B.Fab")
			(effects
				(font
					(size 1.27 1.27)
				)
				(justify mirror)
			)
		)
		(duplicate_pad_numbers_are_jumpers no)
		(fp_line
			(start -0.7874 0.4064)
			(end 0.7874 0.4064)
			(stroke
				(width 0.1524)
				(type default)
			)
			(layer "B.SilkS")
		)
		(fp_line
			(start 0.7874 0.4064)
			(end 0.7874 -0.4064)
			(stroke
				(width 0.1524)
				(type default)
			)
			(layer "B.SilkS")
		)
		(fp_line
			(start -0.7874 -0.4064)
			(end -0.7874 0.4064)
			(stroke
				(width 0.1524)
				(type default)
			)
			(layer "B.SilkS")
		)
		(fp_line
			(start 0.7874 -0.4064)
			(end -0.7874 -0.4064)
			(stroke
				(width 0.1524)
				(type default)
			)
			(layer "B.SilkS")
		)
		(fp_line
			(start -0.67945 0.3048)
			(end -0.120396 0.3048)
			(stroke
				(width 0.1)
				(type default)
			)
			(layer "B.Fab")
		)
		(fp_line
			(start -0.120396 0.3048)
			(end -0.120396 0.2794)
			(stroke
				(width 0.1)
				(type default)
			)
			(layer "B.Fab")
		)
		(fp_line
			(start 0.12065 0.3048)
			(end 0.67945 0.3048)
			(stroke
				(width 0.1)
				(type default)
			)
			(layer "B.Fab")
		)
		(fp_line
			(start 0.67945 0.3048)
			(end 0.67945 -0.305054)
			(stroke
				(width 0.1)
				(type default)
			)
			(layer "B.Fab")
		)
		(fp_line
			(start -0.120396 0.2794)
			(end 0.12065 0.2794)
			(stroke
				(width 0.1)
				(type default)
			)
			(layer "B.Fab")
		)
		(fp_line
			(start 0.12065 0.2794)
			(end 0.12065 0.3048)
			(stroke
				(width 0.1)
				(type default)
			)
			(layer "B.Fab")
		)
		(fp_line
			(start -0.12065 -0.2794)
			(end -0.12065 -0.3048)
			(stroke
				(width 0.1)
				(type default)
			)
			(layer "B.Fab")
		)
		(fp_line
			(start 0.12065 -0.2794)
			(end -0.12065 -0.2794)
			(stroke
				(width 0.1)
				(type default)
			)
			(layer "B.Fab")
		)
		(fp_line
			(start -0.67945 -0.3048)
			(end -0.67945 0.3048)
			(stroke
				(width 0.1)
				(type default)
			)
			(layer "B.Fab")
		)
		(fp_line
			(start -0.12065 -0.3048)
			(end -0.67945 -0.3048)
			(stroke
				(width 0.1)
				(type default)
			)
			(layer "B.Fab")
		)
		(fp_line
			(start 0.12065 -0.305054)
			(end 0.12065 -0.2794)
			(stroke
				(width 0.1)
				(type default)
			)
			(layer "B.Fab")
		)
		(fp_line
			(start 0.67945 -0.305054)
			(end 0.12065 -0.305054)
			(stroke
				(width 0.1)
				(type default)
			)
			(layer "B.Fab")
		)
		(pad "1" smd circle
			(at 0.40005 0 90)
			(size 0 0)
			(layers "B.Cu" "B.Mask" "B.Paste")
			(net "UART_BMC_5_TXD_BUF")
		)
		(pad "2" smd circle
			(at -0.40005 0 90)
			(size 0 0)
			(layers "B.Cu" "B.Mask" "B.Paste")
			(net "UART_BMC_5_TXD_BUF_R")
		)
	)
	(footprint ""
		(layer "B.Cu")
		(at 39.497 -6.731 -90)
		(property "Reference" "R85"
			(at 0 0 90)
			(layer "B.SilkS")
			(hide yes)
			(effects
				(font
					(size 1.27 1.27)
				)
				(justify mirror)
			)
		)
		(property "Value" ""
			(at 0 0 90)
			(layer "B.Fab")
			(effects
				(font
					(size 1.27 1.27)
				)
				(justify mirror)
			)
		)
		(duplicate_pad_numbers_are_jumpers no)
		(fp_line
			(start -0.7874 0.4064)
			(end 0.7874 0.4064)
			(stroke
				(width 0.1524)
				(type default)
			)
			(layer "B.SilkS")
		)
		(fp_line
			(start 0.7874 0.4064)
			(end 0.7874 -0.4064)
			(stroke
				(width 0.1524)
				(type default)
			)
			(layer "B.SilkS")
		)
		(fp_line
			(start -0.7874 -0.4064)
			(end -0.7874 0.4064)
			(stroke
				(width 0.1524)
				(type default)
			)
			(layer "B.SilkS")
		)
		(fp_line
			(start 0.7874 -0.4064)
			(end -0.7874 -0.4064)
			(stroke
				(width 0.1524)
				(type default)
			)
			(layer "B.SilkS")
		)
		(fp_line
			(start -0.67945 0.3048)
			(end -0.120396 0.3048)
			(stroke
				(width 0.1)
				(type default)
			)
			(layer "B.Fab")
		)
		(fp_line
			(start -0.120396 0.3048)
			(end -0.120396 0.2794)
			(stroke
				(width 0.1)
				(type default)
			)
			(layer "B.Fab")
		)
		(fp_line
			(start 0.12065 0.3048)
			(end 0.67945 0.3048)
			(stroke
				(width 0.1)
				(type default)
			)
			(layer "B.Fab")
		)
		(fp_line
			(start 0.67945 0.3048)
			(end 0.67945 -0.305054)
			(stroke
				(width 0.1)
				(type default)
			)
			(layer "B.Fab")
		)
		(fp_line
			(start -0.120396 0.2794)
			(end 0.12065 0.2794)
			(stroke
				(width 0.1)
				(type default)
			)
			(layer "B.Fab")
		)
		(fp_line
			(start 0.12065 0.2794)
			(end 0.12065 0.3048)
			(stroke
				(width 0.1)
				(type default)
			)
			(layer "B.Fab")
		)
		(fp_line
			(start -0.12065 -0.2794)
			(end -0.12065 -0.3048)
			(stroke
				(width 0.1)
				(type default)
			)
			(layer "B.Fab")
		)
		(fp_line
			(start 0.12065 -0.2794)
			(end -0.12065 -0.2794)
			(stroke
				(width 0.1)
				(type default)
			)
			(layer "B.Fab")
		)
		(fp_line
			(start -0.67945 -0.3048)
			(end -0.67945 0.3048)
			(stroke
				(width 0.1)
				(type default)
			)
			(layer "B.Fab")
		)
		(fp_line
			(start -0.12065 -0.3048)
			(end -0.67945 -0.3048)
			(stroke
				(width 0.1)
				(type default)
			)
			(layer "B.Fab")
		)
		(fp_line
			(start 0.12065 -0.305054)
			(end 0.12065 -0.2794)
			(stroke
				(width 0.1)
				(type default)
			)
			(layer "B.Fab")
		)
		(fp_line
			(start 0.67945 -0.305054)
			(end 0.12065 -0.305054)
			(stroke
				(width 0.1)
				(type default)
			)
			(layer "B.Fab")
		)
		(pad "1" smd circle
			(at 0.40005 0 90)
			(size 0 0)
			(layers "B.Cu" "B.Mask" "B.Paste")
			(net "V_VGAHS_BUF_R")
		)
		(pad "2" smd circle
			(at -0.40005 0 90)
			(size 0 0)
			(layers "B.Cu" "B.Mask" "B.Paste")
			(net "V_VGAHS_BUF")
		)
	)
)
